FILE_TYPE = CONNECTIVITY;
{Allegro Design Entry HDL 17.2-2016 S081 (4005846) 1/11/2022}
"PAGE_NUMBER" = 97;
0"NC";
1"M_A_CPU1_SA_CB<7:0>";
2"M_A_CPU1_SB_CA<6:0>";
3"M_A_CPU1_SA_CA<6:0>";
4"M_A_CPU1_SB_CB<7:0>";
5"M_A_CPU1_SA_DQ<31:0>";
6"M_A_CPU1_SB_DQ<31:0>";
7"M_A_CPU1_SA_DQS_DP<9:0>";
8"M_A_CPU1_SB_DQS_DN<9:0>";
9"M_A_CPU1_SB_DQS_DP<9:0>";
10"GND\g";
11"GND\g";
12"P3V3_STBY\g";
13"P3V3_STBY\g";
14"M_A_CPU1_SA_DQS_DN<9:0>";
15"I3C_SPD_DDRAF_CPU1_SCL";
16"I3C_SPD_DDRA_CPU1_SCL";
17"PWRGD_CHA_CPU1_DIMM0";
18"TP_CHA_CPU1_DIMM0_RFU_6";
19"I3C_SPD_DDRAF_CPU1_SDA";
20"P3V3_STBY\g";
21"PD_CHA_CPU1_DIMM0_SAA";
22"M_A_CPU1_ALERT_N";
23"M_A_CPU1_RESET_N";
24"TP_CHA_CPU1_DIMM0_RFU_0";
25"TP_CHA_CPU1_DIMM0_RFU_1";
26"TP_CHA_CPU1_DIMM0_RFU_2";
27"TP_CHA_CPU1_DIMM0_RFU_3";
28"TP_CHA_CPU1_DIMM0_RFU_4";
29"M_A_CPU1_SA_CA<6>";
30"M_A_CPU1_SA_CA<3>";
31"M_A_CPU1_SA_CA<1>";
32"GND\g";
33"P12V_MEM_2\g";
34"GND\g";
35"M_A_CPU1_SA_DQS_DP<9>";
36"M_A_CPU1_SA_DQ<21>";
37"M_A_CPU1_SA_DQ<22>";
38"M_A_CPU1_SB_DQS_DP<9>";
39"M_A_CPU1_SB_DQS_DN<9>";
40"M_A_CPU1_SA_DQS_DN<9>";
41"M_A_CPU1_SA_DQS_DP<8>";
42"M_A_CPU1_SA_DQS_DN<8>";
43"M_A_CPU1_SB_DQS_DN<7>";
44"M_A_CPU1_SA_DQS_DP<7>";
45"M_A_CPU1_SB_DQS_DP<6>";
46"M_A_CPU1_SB_DQS_DN<6>";
47"M_A_CPU1_SA_DQS_DN<6>";
48"M_A_CPU1_SB_DQS_DP<5>";
49"M_A_CPU1_SB_DQS_DN<5>";
50"M_A_CPU1_SA_DQS_DP<5>";
51"M_A_CPU1_SA_DQS_DN<5>";
52"M_A_CPU1_SB_DQS_DP<4>";
53"M_A_CPU1_SB_DQS_DN<4>";
54"M_A_CPU1_SA_DQS_DP<4>";
55"M_A_CPU1_SA_DQS_DN<4>";
56"M_A_CPU1_SB_DQS_DP<3>";
57"M_A_CPU1_SB_DQS_DN<3>";
58"M_A_CPU1_SA_DQS_DP<3>";
59"M_A_CPU1_SA_DQS_DN<3>";
60"M_A_CPU1_SB_DQS_DP<2>";
61"M_A_CPU1_SB_DQS_DN<2>";
62"M_A_CPU1_SA_DQS_DP<2>";
63"M_A_CPU1_SA_DQS_DN<2>";
64"M_A_CPU1_SB_DQS_DP<1>";
65"M_A_CPU1_SB_DQS_DN<1>";
66"M_A_CPU1_SA_DQS_DP<1>";
67"M_A_CPU1_SA_DQS_DN<1>";
68"M_A_CPU1_SB_DQS_DP<0>";
69"M_A_CPU1_SB_DQS_DN<0>";
70"M_A_CPU1_SA_DQS_DP<0>";
71"M_A_CPU1_SA_DQS_DN<0>";
72"M_A_CPU1_SB_DQS_DP<7>";
73"M_A_CPU1_SB_DQS_DN<8>";
74"M_A_CPU1_SB_DQS_DP<8>";
75"M_A_CPU1_SA_DQS_DP<6>";
76"M_A_CPU1_SA_DQS_DN<7>";
77"M_A_CPU1_SA_DQ<17>";
78"M_A_CPU1_SA_DQ<18>";
79"M_A_CPU1_SA_DQ<24>";
80"M_A_CPU1_SA_CA<0>";
81"M_A_CPU1_SA_DQ<27>";
82"M_A_CPU1_SA_DQ<28>";
83"TP_CHA_CPU1_DIMM0_RFU_5";
84"M_A_CPU1_SB_PAR";
85"M_A_CPU1_SA_PAR";
86"M_A_CPU1_SB_RSP<0>";
87"M_A_CPU1_SA_RSP<0>";
88"M_A_CPU1_SB_DQ<0>";
89"M_A_CPU1_SB_DQ<1>";
90"M_A_CPU1_SB_DQ<2>";
91"M_A_CPU1_SB_DQ<3>";
92"M_A_CPU1_SB_DQ<4>";
93"M_A_CPU1_SB_DQ<5>";
94"M_A_CPU1_SB_DQ<6>";
95"M_A_CPU1_SB_DQ<7>";
96"M_A_CPU1_SB_DQ<8>";
97"M_A_CPU1_SB_DQ<9>";
98"M_A_CPU1_SB_DQ<10>";
99"M_A_CPU1_SB_DQ<11>";
100"M_A_CPU1_SB_DQ<12>";
101"M_A_CPU1_SB_DQ<13>";
102"M_A_CPU1_SB_DQ<14>";
103"M_A_CPU1_SB_DQ<15>";
104"M_A_CPU1_SB_DQ<16>";
105"M_A_CPU1_SB_DQ<17>";
106"M_A_CPU1_SB_DQ<18>";
107"M_A_CPU1_SB_DQ<19>";
108"M_A_CPU1_SB_DQ<20>";
109"M_A_CPU1_SB_DQ<21>";
110"M_A_CPU1_SB_DQ<22>";
111"M_A_CPU1_SB_DQ<23>";
112"M_A_CPU1_SB_DQ<24>";
113"M_A_CPU1_SB_DQ<25>";
114"M_A_CPU1_SB_DQ<26>";
115"M_A_CPU1_SB_DQ<27>";
116"M_A_CPU1_SB_DQ<28>";
117"M_A_CPU1_SB_DQ<29>";
118"M_A_CPU1_SB_DQ<30>";
119"M_A_CPU1_SB_DQ<31>";
120"M_A_CPU1_SA_DQ<0>";
121"M_A_CPU1_SA_DQ<1>";
122"M_A_CPU1_SA_DQ<2>";
123"M_A_CPU1_SA_DQ<3>";
124"M_A_CPU1_SA_DQ<4>";
125"M_A_CPU1_SA_DQ<5>";
126"M_A_CPU1_SA_DQ<6>";
127"M_A_CPU1_SA_DQ<7>";
128"M_A_CPU1_SA_DQ<8>";
129"M_A_CPU1_SA_DQ<9>";
130"M_A_CPU1_SA_DQ<10>";
131"M_A_CPU1_SA_DQ<11>";
132"M_A_CPU1_SA_DQ<12>";
133"M_A_CPU1_SA_DQ<13>";
134"M_A_CPU1_SA_DQ<14>";
135"M_A_CPU1_SA_DQ<15>";
136"M_A_CPU1_SA_DQ<16>";
137"M_A_CPU1_SA_DQ<19>";
138"M_A_CPU1_SA_DQ<20>";
139"M_A_CPU1_SA_DQ<23>";
140"M_A_CPU1_SA_DQ<25>";
141"M_A_CPU1_SA_DQ<26>";
142"M_A_CPU1_SA_DQ<29>";
143"M_A_CPU1_SA_DQ<30>";
144"M_A_CPU1_SB_CS_N<1>";
145"M_A_CPU1_SA_CS_N<1>";
146"M_A_CPU1_SB_CS_N<0>";
147"M_A_CPU1_SA_CS_N<0>";
148"M_A_CPU1_CLK_DP<0>";
149"M_A_CPU1_CLK_DN<0>";
150"M_A_CPU1_SB_CB<0>";
151"M_A_CPU1_SB_CB<1>";
152"M_A_CPU1_SB_CB<2>";
153"M_A_CPU1_SB_CB<3>";
154"M_A_CPU1_SB_CB<4>";
155"M_A_CPU1_SB_CB<5>";
156"M_A_CPU1_SB_CB<6>";
157"M_A_CPU1_SA_CB<0>";
158"M_A_CPU1_SA_CB<2>";
159"M_A_CPU1_SA_CB<3>";
160"M_A_CPU1_SA_CB<5>";
161"M_A_CPU1_SA_CB<6>";
162"M_A_CPU1_SB_CA<6>";
163"M_A_CPU1_SB_CA<5>";
164"M_A_CPU1_SA_CA<5>";
165"M_A_CPU1_SB_CA<4>";
166"M_A_CPU1_SA_CA<4>";
167"M_A_CPU1_SB_CA<3>";
168"M_A_CPU1_SB_CA<2>";
169"M_A_CPU1_SA_CA<2>";
170"M_A_CPU1_SB_CA<1>";
171"M_A_CPU1_SB_CA<0>";
172"M_A_CPU1_SB_CB<7>";
173"M_A_CPU1_SA_CB<1>";
174"M_A_CPU1_SA_CB<4>";
175"M_A_CPU1_SA_CB<7>";
176"M_A_CPU1_SA_DQ<31>";
177"PWRGD_CHAF_CPU1";
178"PD_CHA_CPU1_DIMM0_SAA";
179"GND\g";
%"TAP"
"1","(-5750,4175)","0","mstr_standard","I100";
;
CDS_LIB"mstr_standard"
BODY_TYPE"PLUMBING"
HDL_TAP"TRUE";
"B \NAC \NWC"5;
"S \NAC"
BN"5"125;
%"TAP"
"1","(-5750,4325)","0","mstr_standard","I101";
;
CDS_LIB"mstr_standard"
BODY_TYPE"PLUMBING"
HDL_TAP"TRUE";
"B \NAC \NWC"5;
"S \NAC"
BN"8"128;
%"TAP"
"1","(-5750,4375)","0","mstr_standard","I102";
;
CDS_LIB"mstr_standard"
BODY_TYPE"PLUMBING"
HDL_TAP"TRUE";
"B \NAC \NWC"5;
"S \NAC"
BN"9"129;
%"TAP"
"1","(-5750,4275)","0","mstr_standard","I103";
;
CDS_LIB"mstr_standard"
BODY_TYPE"PLUMBING"
HDL_TAP"TRUE";
"B \NAC \NWC"5;
"S \NAC"
BN"7"127;
%"TAP"
"1","(-5750,4525)","0","mstr_standard","I104";
;
CDS_LIB"mstr_standard"
BODY_TYPE"PLUMBING"
HDL_TAP"TRUE";
"B \NAC \NWC"5;
"S \NAC"
BN"12"132;
%"TAP"
"1","(-5750,4475)","0","mstr_standard","I105";
;
CDS_LIB"mstr_standard"
BODY_TYPE"PLUMBING"
HDL_TAP"TRUE";
"B \NAC \NWC"5;
"S \NAC"
BN"11"131;
%"TAP"
"1","(-5750,4425)","0","mstr_standard","I106";
;
CDS_LIB"mstr_standard"
BODY_TYPE"PLUMBING"
HDL_TAP"TRUE";
"B \NAC \NWC"5;
"S \NAC"
BN"10"130;
%"TAP"
"1","(-5750,4575)","0","mstr_standard","I107";
;
CDS_LIB"mstr_standard"
BODY_TYPE"PLUMBING"
HDL_TAP"TRUE";
"B \NAC \NWC"5;
"S \NAC"
BN"13"133;
%"TAP"
"1","(-5750,4625)","0","mstr_standard","I108";
;
CDS_LIB"mstr_standard"
BODY_TYPE"PLUMBING"
HDL_TAP"TRUE";
"B \NAC \NWC"5;
"S \NAC"
BN"14"134;
%"TAP"
"1","(-5750,4775)","0","mstr_standard","I109";
;
CDS_LIB"mstr_standard"
BODY_TYPE"PLUMBING"
HDL_TAP"TRUE";
"B \NAC \NWC"5;
"S \NAC"
BN"17"77;
%"TAP"
"1","(-5750,4725)","0","mstr_standard","I110";
;
CDS_LIB"mstr_standard"
BODY_TYPE"PLUMBING"
HDL_TAP"TRUE";
"B \NAC \NWC"5;
"S \NAC"
BN"16"136;
%"TAP"
"1","(-5750,4675)","0","mstr_standard","I111";
;
CDS_LIB"mstr_standard"
BODY_TYPE"PLUMBING"
HDL_TAP"TRUE";
"B \NAC \NWC"5;
"S \NAC"
BN"15"135;
%"TAP"
"1","(-5750,4825)","0","mstr_standard","I112";
;
CDS_LIB"mstr_standard"
BODY_TYPE"PLUMBING"
HDL_TAP"TRUE";
"B \NAC \NWC"5;
"S \NAC"
BN"18"78;
%"TAP"
"1","(-5750,4875)","0","mstr_standard","I113";
;
CDS_LIB"mstr_standard"
BODY_TYPE"PLUMBING"
HDL_TAP"TRUE";
"B \NAC \NWC"5;
"S \NAC"
BN"19"137;
%"TAP"
"1","(-5750,5025)","0","mstr_standard","I114";
;
CDS_LIB"mstr_standard"
BODY_TYPE"PLUMBING"
HDL_TAP"TRUE";
"B \NAC \NWC"5;
"S \NAC"
BN"22"37;
%"TAP"
"1","(-5750,4975)","0","mstr_standard","I115";
;
CDS_LIB"mstr_standard"
BODY_TYPE"PLUMBING"
HDL_TAP"TRUE";
"B \NAC \NWC"5;
"S \NAC"
BN"21"36;
%"TAP"
"1","(-5750,4925)","0","mstr_standard","I116";
;
CDS_LIB"mstr_standard"
BODY_TYPE"PLUMBING"
HDL_TAP"TRUE";
"B \NAC \NWC"5;
"S \NAC"
BN"20"138;
%"TAP"
"1","(-5750,5125)","0","mstr_standard","I117";
;
CDS_LIB"mstr_standard"
BODY_TYPE"PLUMBING"
HDL_TAP"TRUE";
"B \NAC \NWC"5;
"S \NAC"
BN"24"79;
%"TAP"
"1","(-5750,5075)","0","mstr_standard","I118";
;
CDS_LIB"mstr_standard"
BODY_TYPE"PLUMBING"
HDL_TAP"TRUE";
"B \NAC \NWC"5;
"S \NAC"
BN"23"139;
%"TAP"
"1","(-5750,5225)","0","mstr_standard","I119";
;
CDS_LIB"mstr_standard"
BODY_TYPE"PLUMBING"
HDL_TAP"TRUE";
"B \NAC \NWC"5;
"S \NAC"
BN"26"141;
%"TAP"
"1","(-5750,5275)","0","mstr_standard","I120";
;
CDS_LIB"mstr_standard"
BODY_TYPE"PLUMBING"
HDL_TAP"TRUE";
"B \NAC \NWC"5;
"S \NAC"
BN"27"81;
%"TAP"
"1","(-5750,5175)","0","mstr_standard","I121";
;
CDS_LIB"mstr_standard"
BODY_TYPE"PLUMBING"
HDL_TAP"TRUE";
"B \NAC \NWC"5;
"S \NAC"
BN"25"140;
%"TAP"
"1","(-5750,5425)","0","mstr_standard","I122";
;
CDS_LIB"mstr_standard"
BODY_TYPE"PLUMBING"
HDL_TAP"TRUE";
"B \NAC \NWC"5;
"S \NAC"
BN"30"143;
%"TAP"
"1","(-5750,5325)","0","mstr_standard","I123";
;
CDS_LIB"mstr_standard"
BODY_TYPE"PLUMBING"
HDL_TAP"TRUE";
"B \NAC \NWC"5;
"S \NAC"
BN"28"82;
%"TAP"
"1","(-5750,5375)","0","mstr_standard","I124";
;
CDS_LIB"mstr_standard"
BODY_TYPE"PLUMBING"
HDL_TAP"TRUE";
"B \NAC \NWC"5;
"S \NAC"
BN"29"142;
%"TAP"
"1","(-5750,5475)","0","mstr_standard","I125";
;
CDS_LIB"mstr_standard"
BODY_TYPE"PLUMBING"
HDL_TAP"TRUE";
"B \NAC \NWC"5;
"S \NAC"
BN"31"176;
%"GND"
"1","(-6125,1075)","0","mstr_symbols","I128";
;
BOM_COST"MEM"
CDS_LIB"mstr_symbols"
SIZE"1B"
BODY_TYPE"PLUMBING"
VOLTAGE"0.0"
HDL_POWER"GND";
"A\NAC"10;
%"Q_RES"
"2","(-6125,1300)","0","pure_quanta","I129";
;
LOCATION"R36"
SEC"1"
WATTAGE"1/16W"
MATERIAL"CHIP"
TOLERANCE"1%"
VALUE"10K"
PART_NUMBER"CS31002FB08"
PACK_TYPE"0402LF"
SEC_TYPE"0402LF"
CDS_LIB"pure_quanta"
BOM_COST"MEM"
ROOM"MEM_CH_A_CPU1_DIMM1";
"A"
$PN"1"
XNET_PINS"3"178;
"B"
$PN"2"
XNET_PINS"2"10;
%"GND"
"1","(-2100,2075)","0","mstr_symbols","I130";
;
CDS_LIB"mstr_symbols"
SIZE"1B"
BODY_TYPE"PLUMBING"
VOLTAGE"0.0"
HDL_POWER"GND";
"A\NAC"34;
%"GND"
"1","(-500,1875)","0","mstr_symbols","I146";
;
CDS_LIB"mstr_symbols"
SIZE"1B"
BODY_TYPE"PLUMBING"
VOLTAGE"0.0"
HDL_POWER"GND";
"A\NAC"32;
%"SCONN288_DDR506112002KQ"
"3","(-1300,3825)","0","pure_quanta","I177";
;
LOCATION"J24"
$SEC"3"
CDS_SEC"3"
VALUE"SCONN288_DDR506112002KQ"
PART_TYPE"SMLF"
PART_NUMBER"DFHST8FS479"
MATERIAL"IO"
CDS_LMAN_SYM_OUTLINE"-450,1800,450,-1750"
NEEDS_NO_SIZE"TRUE"
CDS_LIB"pure_quanta";
"G3"
$PN"G3"32;
"G2"
$PN"G2"32;
"G1"
$PN"G1"32;
"VSS62"
$PN"141"32;
"VSS61"
$PN"139"32;
"VSS60"
$PN"136"32;
"VSS58"
$PN"132"32;
"VSS104"
$PN"240"34;
"VSS102"
$PN"235"34;
"VSS100"
$PN"230"34;
"VIN_BULK2"
$PN"146"33;
"VIN_BULK1"
$PN"145"33;
"VIN_BULK0"
$PN"1"33;
"VSS126"
$PN"288"34;
"VSS125"
$PN"286"34;
"VSS124"
$PN"284"34;
"VSS123"
$PN"281"34;
"VSS122"
$PN"279"34;
"VSS121"
$PN"277"34;
"VSS120"
$PN"275"34;
"VSS119"
$PN"273"34;
"VSS118"
$PN"270"34;
"VSS117"
$PN"268"34;
"VSS116"
$PN"266"34;
"VSS115"
$PN"264"34;
"VSS114"
$PN"262"34;
"VSS113"
$PN"259"34;
"VSS112"
$PN"257"34;
"VSS111"
$PN"255"34;
"VSS110"
$PN"253"34;
"VSS109"
$PN"251"34;
"VSS108"
$PN"248"34;
"VSS107"
$PN"246"34;
"VSS106"
$PN"244"34;
"VSS105"
$PN"242"34;
"VSS103"
$PN"237"34;
"VSS101"
$PN"233"34;
"VSS99"
$PN"228"34;
"VSS98"
$PN"226"34;
"VSS97"
$PN"224"34;
"VSS96"
$PN"222"34;
"VSS95"
$PN"219"34;
"VSS94"
$PN"216"34;
"VSS93"
$PN"214"34;
"VSS92"
$PN"212"34;
"VSS91"
$PN"210"34;
"VSS90"
$PN"208"34;
"VSS89"
$PN"206"34;
"VSS88"
$PN"204"34;
"VSS87"
$PN"202"34;
"VSS86"
$PN"199"34;
"VSS85"
$PN"197"34;
"VSS84"
$PN"195"34;
"VSS83"
$PN"193"34;
"VSS82"
$PN"191"34;
"VSS81"
$PN"188"34;
"VSS80"
$PN"186"34;
"VSS79"
$PN"184"34;
"VSS78"
$PN"182"34;
"VSS77"
$PN"180"34;
"VSS76"
$PN"177"34;
"VSS75"
$PN"175"34;
"VSS74"
$PN"173"34;
"VSS73"
$PN"171"34;
"VSS72"
$PN"169"34;
"VSS71"
$PN"166"34;
"VSS70"
$PN"164"34;
"VSS69"
$PN"162"34;
"VSS68"
$PN"160"34;
"VSS67"
$PN"158"34;
"VSS66"
$PN"155"34;
"VSS65"
$PN"153"34;
"VSS64"
$PN"151"34;
"VSS63"
$PN"143"32;
"VSS59"
$PN"134"32;
"VSS57"
$PN"130"32;
"VSS56"
$PN"128"32;
"VSS55"
$PN"125"32;
"VSS54"
$PN"123"32;
"VSS53"
$PN"121"32;
"VSS52"
$PN"119"32;
"VSS51"
$PN"117"32;
"VSS50"
$PN"114"32;
"VSS49"
$PN"112"32;
"VSS48"
$PN"110"32;
"VSS47"
$PN"108"32;
"VSS46"
$PN"106"32;
"VSS45"
$PN"103"32;
"VSS44"
$PN"101"32;
"VSS43"
$PN"99"32;
"VSS42"
$PN"97"32;
"VSS41"
$PN"95"32;
"VSS40"
$PN"92"32;
"VSS39"
$PN"90"32;
"VSS38"
$PN"88"32;
"VSS37"
$PN"85"32;
"VSS36"
$PN"83"32;
"VSS35"
$PN"81"32;
"VSS34"
$PN"79"32;
"VSS33"
$PN"77"32;
"VSS32"
$PN"75"32;
"VSS31"
$PN"73"32;
"VSS30"
$PN"71"32;
"VSS29"
$PN"69"32;
"VSS28"
$PN"67"32;
"VSS27"
$PN"65"32;
"VSS26"
$PN"63"32;
"VSS25"
$PN"61"32;
"VSS24"
$PN"59"32;
"VSS23"
$PN"57"32;
"VSS22"
$PN"54"32;
"VSS21"
$PN"52"32;
"VSS20"
$PN"50"32;
"VSS19"
$PN"48"32;
"VSS18"
$PN"46"32;
"VSS17"
$PN"43"32;
"VSS16"
$PN"41"32;
"VSS15"
$PN"39"32;
"VSS14"
$PN"37"32;
"VSS13"
$PN"35"32;
"VSS12"
$PN"32"32;
"VSS11"
$PN"30"32;
"VSS10"
$PN"28"32;
"VSS9"
$PN"26"32;
"VSS8"
$PN"24"32;
"VSS7"
$PN"21"32;
"VSS6"
$PN"19"32;
"VSS5"
$PN"17"32;
"VSS4"
$PN"15"32;
"VSS3"
$PN"13"32;
"VSS2"
$PN"10"32;
"VSS1"
$PN"8"32;
"VSS0"
$PN"6"32;
%"Q_CAP"
"1","(-8600,3325)","2","pure_quanta","I185";
;
LOCATION"C136"
$SEC"1"
CDS_SEC"1"
MATERIAL"X7R"
TOLERANCE"10%"
VALUE"0.1UF"
VOLTAGE"25V"
PACK_TYPE"0402"
PART_NUMBER"CH4104K1B00"
CDS_LIB"pure_quanta"
BOM_COST"MEM"
ROOM"MEM_CH_A_CPU0_DIMM1";
"B"
$PN"2"11;
"A"
$PN"1"20;
%"GND"
"1","(-8600,3100)","0","mstr_symbols","I186";
;
CDS_LIB"mstr_symbols"
SIZE"1B"
BOM_COST"MEM"
BODY_TYPE"PLUMBING"
VOLTAGE"0"
ROOM"MEM_EFGH_DECOUPLING_CAPS"
HDL_POWER"GND";
"A\NAC"11;
%"VCC_CORE"
"1","(-8525,2550)","0","mstr_symbols","I188";
;
HDL_POWER"P3V3_STBY"
CDS_LIB"mstr_symbols"
VOLTAGE"3.3"
ROOM"PVCCINFAON_CPU0_CTRL";
"A"12;
%"Q_RES"
"2","(-8525,2375)","2","pure_quanta","I189";
;
LOCATION"R102"
$SEC"1"
CDS_SEC"1"
WATTAGE"1/16W"
MATERIAL"CHIP"
TOLERANCE"5%"
VALUE"1K"
PART_NUMBER"TMP_QCS21002JB34"
PACK_TYPE"0402LF"
BOM_COST"MEM"
CDS_LIB"pure_quanta"
ROOM"MEM_CH_A_CPU0_DIMM1";
"A"
$PN"1"12;
"B"
$PN"2"177;
%"Q_RES"
"1","(-8400,2225)","2","pure_quanta","I190";
;
LOCATION"R303"
$SEC"1"
CDS_SEC"1"
VALUE"0"
CDS_LIB"pure_quanta"
BOM_COST"MEM"
WATTAGE"1/16W"
MATERIAL"CHIP"
TOLERANCE"5%"
PART_NUMBER"CS00002JB38"
PACK_TYPE"0402LF"
ROOM"RST_CPU0_PLD_TO_DIMM";
"B"
$PN"2"177;
"A"
$PN"1"17;
%"Q_RES"
"2","(-8275,2375)","0","pure_quanta","I191";
;
LOCATION"R103"
$SEC"1"
CDS_SEC"1"
TOLERANCE"5%"
VALUE"1K"
PACK_TYPE"0402LF"
MATERIAL"EMPTY"
WATTAGE"1/16W"
BOM_COST"MEM"
CDS_LIB"pure_quanta"
PART_NUMBER"TMP_QCS21002JB34"
ROOM"MEM_CH_A_CPU0_DIMM1";
"A"
$PN"1"13;
"B"
$PN"2"17;
%"VCC_CORE"
"1","(-8275,2550)","0","mstr_symbols","I192";
;
HDL_POWER"P3V3_STBY"
CDS_LIB"mstr_symbols"
VOLTAGE"3.3"
ROOM"PVCCINFAON_CPU0_CTRL";
"A"13;
%"TAP"
"1","(-3025,4550)","0","mstr_standard","I198";
;
CDS_LIB"mstr_standard"
BODY_TYPE"PLUMBING"
HDL_TAP"TRUE";
"B \NAC \NWC"14;
"S \NAC"
BN"9"40;
%"TAP"
"1","(-3025,4450)","0","mstr_standard","I199";
;
CDS_LIB"mstr_standard"
BODY_TYPE"PLUMBING"
HDL_TAP"TRUE";
"B \NAC \NWC"14;
"S \NAC"
BN"8"42;
%"TAP"
"1","(-3025,4350)","0","mstr_standard","I200";
;
CDS_LIB"mstr_standard"
BODY_TYPE"PLUMBING"
HDL_TAP"TRUE";
"B \NAC \NWC"14;
"S \NAC"
BN"7"76;
%"TAP"
"1","(-3225,4600)","0","mstr_standard","I201";
;
CDS_LIB"mstr_standard"
BODY_TYPE"PLUMBING"
HDL_TAP"TRUE";
"B \NAC \NWC"7;
"S \NAC"
BN"9"35;
%"TAP"
"1","(-3225,4500)","0","mstr_standard","I202";
;
CDS_LIB"mstr_standard"
BODY_TYPE"PLUMBING"
HDL_TAP"TRUE";
"B \NAC \NWC"7;
"S \NAC"
BN"8"41;
%"TAP"
"1","(-3225,4400)","0","mstr_standard","I203";
;
CDS_LIB"mstr_standard"
BODY_TYPE"PLUMBING"
HDL_TAP"TRUE";
"B \NAC \NWC"7;
"S \NAC"
BN"7"44;
%"TAP"
"1","(-3025,4250)","0","mstr_standard","I204";
;
CDS_LIB"mstr_standard"
BODY_TYPE"PLUMBING"
HDL_TAP"TRUE";
"B \NAC \NWC"14;
"S \NAC"
BN"6"47;
%"TAP"
"1","(-3025,4150)","0","mstr_standard","I205";
;
CDS_LIB"mstr_standard"
BODY_TYPE"PLUMBING"
HDL_TAP"TRUE";
"B \NAC \NWC"14;
"S \NAC"
BN"5"51;
%"TAP"
"1","(-3025,3950)","0","mstr_standard","I206";
;
CDS_LIB"mstr_standard"
BODY_TYPE"PLUMBING"
HDL_TAP"TRUE";
"B \NAC \NWC"14;
"S \NAC"
BN"3"59;
%"TAP"
"1","(-3025,4050)","0","mstr_standard","I207";
;
CDS_LIB"mstr_standard"
BODY_TYPE"PLUMBING"
HDL_TAP"TRUE";
"B \NAC \NWC"14;
"S \NAC"
BN"4"55;
%"TAP"
"1","(-3025,3850)","0","mstr_standard","I208";
;
CDS_LIB"mstr_standard"
BODY_TYPE"PLUMBING"
HDL_TAP"TRUE";
"B \NAC \NWC"14;
"S \NAC"
BN"2"63;
%"TAP"
"1","(-3225,4100)","0","mstr_standard","I209";
;
CDS_LIB"mstr_standard"
BODY_TYPE"PLUMBING"
HDL_TAP"TRUE";
"B \NAC \NWC"7;
"S \NAC"
BN"4"54;
%"TAP"
"1","(-3225,4200)","0","mstr_standard","I210";
;
CDS_LIB"mstr_standard"
BODY_TYPE"PLUMBING"
HDL_TAP"TRUE";
"B \NAC \NWC"7;
"S \NAC"
BN"5"50;
%"TAP"
"1","(-3225,4300)","0","mstr_standard","I211";
;
CDS_LIB"mstr_standard"
BODY_TYPE"PLUMBING"
HDL_TAP"TRUE";
"B \NAC \NWC"7;
"S \NAC"
BN"6"75;
%"TAP"
"1","(-3225,4000)","0","mstr_standard","I212";
;
CDS_LIB"mstr_standard"
BODY_TYPE"PLUMBING"
HDL_TAP"TRUE";
"B \NAC \NWC"7;
"S \NAC"
BN"3"58;
%"TAP"
"1","(-3225,3900)","0","mstr_standard","I213";
;
CDS_LIB"mstr_standard"
BODY_TYPE"PLUMBING"
HDL_TAP"TRUE";
"B \NAC \NWC"7;
"S \NAC"
BN"2"62;
%"TAP"
"1","(-3025,3750)","0","mstr_standard","I214";
;
CDS_LIB"mstr_standard"
BODY_TYPE"PLUMBING"
HDL_TAP"TRUE";
"B \NAC \NWC"14;
"S \NAC"
BN"1"67;
%"TAP"
"1","(-3025,3650)","0","mstr_standard","I215";
;
CDS_LIB"mstr_standard"
BODY_TYPE"PLUMBING"
HDL_TAP"TRUE";
"B \NAC \NWC"14;
"S \NAC"
BN"0"71;
%"TAP"
"1","(-3025,3500)","0","mstr_standard","I216";
;
CDS_LIB"mstr_standard"
BODY_TYPE"PLUMBING"
HDL_TAP"TRUE";
"B \NAC \NWC"8;
"S \NAC"
BN"9"39;
%"TAP"
"1","(-3025,3400)","0","mstr_standard","I217";
;
CDS_LIB"mstr_standard"
BODY_TYPE"PLUMBING"
HDL_TAP"TRUE";
"B \NAC \NWC"8;
"S \NAC"
BN"8"73;
%"TAP"
"1","(-3025,3300)","0","mstr_standard","I218";
;
CDS_LIB"mstr_standard"
BODY_TYPE"PLUMBING"
HDL_TAP"TRUE";
"B \NAC \NWC"8;
"S \NAC"
BN"7"43;
%"TAP"
"1","(-3225,3700)","0","mstr_standard","I219";
;
CDS_LIB"mstr_standard"
BODY_TYPE"PLUMBING"
HDL_TAP"TRUE";
"B \NAC \NWC"7;
"S \NAC"
BN"0"70;
%"SCONN288_DDR506112002KQ"
"1","(-6600,3725)","0","pure_quanta","I22";
;
LOCATION"J24"
$SEC"1"
CDS_SEC"1"
VALUE"SCONN288_DDR506112002KQ"
PART_TYPE"SMLF"
MATERIAL"IO"
PART_NUMBER"DFHST8FS479"
CDS_LMAN_SYM_OUTLINE"-450,1900,450,-1850"
NEEDS_NO_SIZE"TRUE"
CDS_LIB"pure_quanta";
"PWR_GOOD||FAIL_N"
$PN"147"17;
"DQ31_A"
$PN"194"176;
"CB7_A"
$PN"205"175;
"CB4_A"
$PN"58"174;
"CB1_A"
$PN"53"173;
"CB7_B"
$PN"236"172;
"ALERT_N \B"
$PN"62"22;
"CA0_A"
$PN"66"80;
"CA0_B"
$PN"76"171;
"CA1_A"
$PN"211"31;
"CA1_B"
$PN"221"170;
"CA2_A"
$PN"68"169;
"CA2_B"
$PN"78"168;
"CA3_A"
$PN"213"30;
"CA3_B"
$PN"223"167;
"CA4_A"
$PN"70"166;
"CA4_B"
$PN"80"165;
"CA5_A"
$PN"215"164;
"CA5_B"
$PN"225"163;
"CA6_A"
$PN"72"29;
"CA6_B"
$PN"82"162;
"CB6_A"
$PN"203"161;
"CB5_A"
$PN"60"160;
"CB3_A"
$PN"198"159;
"CB2_A"
$PN"196"158;
"CB0_A"
$PN"51"157;
"CB6_B"
$PN"234"156;
"CB5_B"
$PN"91"155;
"CB4_B"
$PN"89"154;
"CB3_B"
$PN"243"153;
"CB2_B"
$PN"241"152;
"CB1_B"
$PN"98"151;
"CB0_B"
$PN"96"150;
"CK_C \B"
$PN"218"149;
"CK_T"
$PN"217"148;
"CS0_A_N"
$PN"64"147;
"CS0_B_N"
$PN"84"146;
"CS1_A_N"
$PN"209"145;
"CS1_B_N"
$PN"229"144;
"DQ30_A"
$PN"192"143;
"DQ29_A"
$PN"49"142;
"DQ28_A"
$PN"47"82;
"DQ27_A"
$PN"187"81;
"DQ26_A"
$PN"185"141;
"DQ25_A"
$PN"42"140;
"DQ24_A"
$PN"40"79;
"DQ23_A"
$PN"183"139;
"DQ22_A"
$PN"181"37;
"DQ21_A"
$PN"38"36;
"DQ20_A"
$PN"36"138;
"DQ19_A"
$PN"176"137;
"DQ18_A"
$PN"174"78;
"DQ17_A"
$PN"31"77;
"DQ16_A"
$PN"29"136;
"DQ15_A"
$PN"172"135;
"DQ14_A"
$PN"170"134;
"DQ13_A"
$PN"27"133;
"DQ12_A"
$PN"25"132;
"DQ11_A"
$PN"165"131;
"DQ10_A"
$PN"163"130;
"DQ9_A"
$PN"20"129;
"DQ8_A"
$PN"18"128;
"DQ7_A"
$PN"161"127;
"DQ6_A"
$PN"159"126;
"DQ5_A"
$PN"16"125;
"DQ4_A"
$PN"14"124;
"DQ3_A"
$PN"154"123;
"DQ2_A"
$PN"152"122;
"DQ1_A"
$PN"9"121;
"DQ0_A"
$PN"7"120;
"DQ31_B"
$PN"287"119;
"DQ30_B"
$PN"285"118;
"DQ29_B"
$PN"142"117;
"DQ28_B"
$PN"140"116;
"DQ27_B"
$PN"280"115;
"DQ26_B"
$PN"278"114;
"DQ25_B"
$PN"135"113;
"DQ24_B"
$PN"133"112;
"DQ23_B"
$PN"276"111;
"DQ22_B"
$PN"274"110;
"DQ21_B"
$PN"131"109;
"DQ20_B"
$PN"129"108;
"DQ19_B"
$PN"269"107;
"DQ18_B"
$PN"267"106;
"DQ17_B"
$PN"124"105;
"DQ16_B"
$PN"122"104;
"DQ15_B"
$PN"265"103;
"DQ14_B"
$PN"263"102;
"DQ13_B"
$PN"120"101;
"DQ12_B"
$PN"118"100;
"DQ11_B"
$PN"258"99;
"DQ10_B"
$PN"256"98;
"DQ9_B"
$PN"113"97;
"DQ8_B"
$PN"111"96;
"DQ7_B"
$PN"254"95;
"DQ6_B"
$PN"252"94;
"DQ5_B"
$PN"109"93;
"DQ4_B"
$PN"107"92;
"DQ3_B"
$PN"247"91;
"DQ2_B"
$PN"245"90;
"DQ1_B"
$PN"102"89;
"DQ0_B"
$PN"100"88;
"HAS"
$PN"148"21;
"HSCL"
$PN"4"16;
"HSDA"
$PN"5"19;
"LBD||RSP_A_N"
$PN"86"87;
"LBS||RSP_B_N"
$PN"87"86;
"PAR_A"
$PN"74"85;
"PAR_B"
$PN"227"84;
"RESET_N \B"
$PN"207"23;
"RFU6"
$PN"232"18;
"RFU5"
$PN"231"83;
"RFU4"
$PN"220"28;
"RFU3"
$PN"150"27;
"RFU2"
$PN"149"26;
"RFU1"
$PN"144"25;
"RFU0"
$PN"2"24;
"VIN_MGMT"
$PN"3"20;
%"TAP"
"1","(-3225,3800)","0","mstr_standard","I220";
;
CDS_LIB"mstr_standard"
BODY_TYPE"PLUMBING"
HDL_TAP"TRUE";
"B \NAC \NWC"7;
"S \NAC"
BN"1"66;
%"TAP"
"1","(-3225,3550)","0","mstr_standard","I221";
;
CDS_LIB"mstr_standard"
BODY_TYPE"PLUMBING"
HDL_TAP"TRUE";
"B \NAC \NWC"9;
"S \NAC"
BN"9"38;
%"TAP"
"1","(-3225,3450)","0","mstr_standard","I222";
;
CDS_LIB"mstr_standard"
BODY_TYPE"PLUMBING"
HDL_TAP"TRUE";
"B \NAC \NWC"9;
"S \NAC"
BN"8"74;
%"TAP"
"1","(-3225,3350)","0","mstr_standard","I223";
;
CDS_LIB"mstr_standard"
BODY_TYPE"PLUMBING"
HDL_TAP"TRUE";
"B \NAC \NWC"9;
"S \NAC"
BN"7"72;
%"TAP"
"1","(-3025,3200)","0","mstr_standard","I224";
;
CDS_LIB"mstr_standard"
BODY_TYPE"PLUMBING"
HDL_TAP"TRUE";
"B \NAC \NWC"8;
"S \NAC"
BN"6"46;
%"TAP"
"1","(-3025,3100)","0","mstr_standard","I225";
;
CDS_LIB"mstr_standard"
BODY_TYPE"PLUMBING"
HDL_TAP"TRUE";
"B \NAC \NWC"8;
"S \NAC"
BN"5"49;
%"TAP"
"1","(-3025,3000)","0","mstr_standard","I226";
;
CDS_LIB"mstr_standard"
BODY_TYPE"PLUMBING"
HDL_TAP"TRUE";
"B \NAC \NWC"8;
"S \NAC"
BN"4"53;
%"TAP"
"1","(-3025,2800)","0","mstr_standard","I227";
;
CDS_LIB"mstr_standard"
BODY_TYPE"PLUMBING"
HDL_TAP"TRUE";
"B \NAC \NWC"8;
"S \NAC"
BN"2"61;
%"TAP"
"1","(-3025,2900)","0","mstr_standard","I228";
;
CDS_LIB"mstr_standard"
BODY_TYPE"PLUMBING"
HDL_TAP"TRUE";
"B \NAC \NWC"8;
"S \NAC"
BN"3"57;
%"TAP"
"1","(-3225,3250)","0","mstr_standard","I229";
;
CDS_LIB"mstr_standard"
BODY_TYPE"PLUMBING"
HDL_TAP"TRUE";
"B \NAC \NWC"9;
"S \NAC"
BN"6"45;
%"TAP"
"1","(-7450,3275)","2","mstr_standard","I23";
;
CDS_LIB"mstr_standard"
BODY_TYPE"PLUMBING"
HDL_TAP"TRUE";
"B \NAC \NWC"4;
"S \NAC"
BN"0"150;
%"TAP"
"1","(-3225,3050)","0","mstr_standard","I230";
;
CDS_LIB"mstr_standard"
BODY_TYPE"PLUMBING"
HDL_TAP"TRUE";
"B \NAC \NWC"9;
"S \NAC"
BN"4"52;
%"TAP"
"1","(-3225,3150)","0","mstr_standard","I231";
;
CDS_LIB"mstr_standard"
BODY_TYPE"PLUMBING"
HDL_TAP"TRUE";
"B \NAC \NWC"9;
"S \NAC"
BN"5"48;
%"TAP"
"1","(-3225,2950)","0","mstr_standard","I232";
;
CDS_LIB"mstr_standard"
BODY_TYPE"PLUMBING"
HDL_TAP"TRUE";
"B \NAC \NWC"9;
"S \NAC"
BN"3"56;
%"TAP"
"1","(-3225,2850)","0","mstr_standard","I233";
;
CDS_LIB"mstr_standard"
BODY_TYPE"PLUMBING"
HDL_TAP"TRUE";
"B \NAC \NWC"9;
"S \NAC"
BN"2"60;
%"TAP"
"1","(-3025,2700)","0","mstr_standard","I234";
;
CDS_LIB"mstr_standard"
BODY_TYPE"PLUMBING"
HDL_TAP"TRUE";
"B \NAC \NWC"8;
"S \NAC"
BN"1"65;
%"TAP"
"1","(-3025,2600)","0","mstr_standard","I235";
;
CDS_LIB"mstr_standard"
BODY_TYPE"PLUMBING"
HDL_TAP"TRUE";
"B \NAC \NWC"8;
"S \NAC"
BN"0"69;
%"TAP"
"1","(-3225,2650)","0","mstr_standard","I236";
;
CDS_LIB"mstr_standard"
BODY_TYPE"PLUMBING"
HDL_TAP"TRUE";
"B \NAC \NWC"9;
"S \NAC"
BN"0"68;
%"TAP"
"1","(-3225,2750)","0","mstr_standard","I237";
;
CDS_LIB"mstr_standard"
BODY_TYPE"PLUMBING"
HDL_TAP"TRUE";
"B \NAC \NWC"9;
"S \NAC"
BN"1"64;
%"SCONN288_DDR506112002KQ"
"2","(-4225,3600)","0","pure_quanta","I238";
;
LOCATION"J24"
$SEC"2"
CDS_SEC"2"
PART_TYPE"SMLF"
VALUE"SCONN288_DDR506112002KQ"
PART_NUMBER"DFHST8FS479"
MATERIAL"IO"
CDS_LMAN_SYM_OUTLINE"-600,1150,600,-1150"
NEEDS_NO_SIZE"TRUE"
CDS_LIB"pure_quanta";
"DQS7_A_C||TDQS7_A_C \B"
$PN"178"76;
"DQS6_A_T||TDQS6_A_T"
$PN"168"75;
"DQS8_B_T||TDQS8_B_T"
$PN"283"74;
"DQS8_B_C||TDQS8_B_C \B"
$PN"282"73;
"DQS7_B_T||TDQS7_B_T"
$PN"272"72;
"DQS0_A_C \B"
$PN"12"71;
"DQS0_A_T"
$PN"11"70;
"DQS0_B_C \B"
$PN"105"69;
"DQS0_B_T"
$PN"104"68;
"DQS1_A_C \B"
$PN"23"67;
"DQS1_A_T"
$PN"22"66;
"DQS1_B_C \B"
$PN"116"65;
"DQS1_B_T"
$PN"115"64;
"DQS2_A_C \B"
$PN"34"63;
"DQS2_A_T"
$PN"33"62;
"DQS2_B_C \B"
$PN"127"61;
"DQS2_B_T"
$PN"126"60;
"DQS3_A_C \B"
$PN"45"59;
"DQS3_A_T"
$PN"44"58;
"DQS3_B_C \B"
$PN"138"57;
"DQS3_B_T"
$PN"137"56;
"DQS4_A_C \B"
$PN"56"55;
"DQS4_A_T"
$PN"55"54;
"DQS4_B_C \B"
$PN"238"53;
"DQS4_B_T"
$PN"239"52;
"DQS5_A_C||TDQS5_A_C||DQS5_A_T||TDQS5_A_T \B"
$PN"156"51;
"DQS5_A_T||TDQS5_A_T"
$PN"157"50;
"DQS5_B_C||TDQS5_B_C \B"
$PN"249"49;
"DQS5_B_T||TDQS5_B_T"
$PN"250"48;
"DQS6_A_C||TDQS6_A_C||DQS6_A_T||TDQS6_A_T \B"
$PN"167"47;
"DQS6_B_C||TDQS6_B_C \B"
$PN"260"46;
"DQS6_B_T||TDQS6_B_T"
$PN"261"45;
"DQS7_A_T||TDQS7_A_T"
$PN"179"44;
"DQS7_B_C||TDQS7_B_C \B"
$PN"271"43;
"DQS8_A_C||TDQS8_A_C \B"
$PN"189"42;
"DQS8_A_T||TDQS8_A_T"
$PN"190"41;
"DQS9_A_C||TDQS9_A_C \B"
$PN"200"40;
"DQS9_A_T||TDQS9_A_T"
$PN"201"35;
"DQS9_B_C||TDQS9_B_C \B"
$PN"94"39;
"DQS9_B_T||TDQS9_B_T||DBI4_B_N"
$PN"93"38;
%"GND"
"1","(-2800,5750)","0","pure_quanta_power","I239";
;
CDS_LIB"pure_quanta_power"
BOM_COST"MEM"
SIZE"1B"
ROOM"MEM_EFGH_DECOUPLING_CAPS"
HDL_POWER"GND";
"A<SIZE-1..0>\NAC"179;
%"TAP"
"1","(-7450,3325)","2","mstr_standard","I24";
;
CDS_LIB"mstr_standard"
BODY_TYPE"PLUMBING"
HDL_TAP"TRUE";
"B \NAC \NWC"4;
"S \NAC"
BN"1"151;
%"Q_CAP"
"1","(-2800,6100)","2","pure_quanta","I240";
;
LOCATION"C173"
$SEC"1"
CDS_SEC"1"
MATERIAL"X6S"
TOLERANCE"10%"
VALUE"10UF"
PART_NUMBER"CH6104KEA00"
VOLTAGE"25V"
PACK_TYPE"C0805"
BOM_COST"MEM"
CDS_LIB"pure_quanta"
ROOM"MEM_CH_A_CPU0_DIMM1";
"B"
$PN"2"179;
"A"
$PN"1"33;
%"Q_CAP"
"1","(-2225,6100)","2","pure_quanta","I241";
;
LOCATION"C174"
$SEC"1"
CDS_SEC"1"
MATERIAL"X6S"
TOLERANCE"10%"
VALUE"10UF"
PART_NUMBER"CH6104KEA00"
VOLTAGE"25V"
PACK_TYPE"C0805"
BOM_COST"MEM"
CDS_LIB"pure_quanta"
ROOM"MEM_CH_A_CPU0_DIMM1";
"B"
$PN"2"179;
"A"
$PN"1"33;
%"UNIVERSAL_POWER"
"1","(-2800,6425)","0","pure_quanta_power","I242";
;
HDL_POWER"P12V_MEM_2"
CDS_LIB"pure_quanta_power";
"A"33;
%"Q_RES"
"1","(-7500,2775)","0","pure_quanta","I244";
;
$LOCATION"R1580"
CDS_LOCATION"R1580"
$SEC"1"
CDS_SEC"1"
VALUE"49.9"
CDS_LIB"pure_quanta"
PART_NUMBER"CS04992FB07"
TOLERANCE"1%"
WATTAGE"1/16W"
PACK_TYPE"0402LF"
MATERIAL"CHIP";
"B"
$PN"2"16;
"A"
$PN"1"15;
%"TAP"
"1","(-7450,3375)","2","mstr_standard","I25";
;
CDS_LIB"mstr_standard"
BODY_TYPE"PLUMBING"
HDL_TAP"TRUE";
"B \NAC \NWC"4;
"S \NAC"
BN"2"152;
%"TAP"
"1","(-7450,3425)","2","mstr_standard","I26";
;
CDS_LIB"mstr_standard"
BODY_TYPE"PLUMBING"
HDL_TAP"TRUE";
"B \NAC \NWC"4;
"S \NAC"
BN"3"153;
%"TAP"
"1","(-7450,3475)","2","mstr_standard","I27";
;
CDS_LIB"mstr_standard"
BODY_TYPE"PLUMBING"
HDL_TAP"TRUE";
"B \NAC \NWC"4;
"S \NAC"
BN"4"154;
%"TAP"
"1","(-7450,3525)","2","mstr_standard","I28";
;
CDS_LIB"mstr_standard"
BODY_TYPE"PLUMBING"
HDL_TAP"TRUE";
"B \NAC \NWC"4;
"S \NAC"
BN"5"155;
%"TAP"
"1","(-7450,3575)","2","mstr_standard","I29";
;
CDS_LIB"mstr_standard"
BODY_TYPE"PLUMBING"
HDL_TAP"TRUE";
"B \NAC \NWC"4;
"S \NAC"
BN"6"156;
%"TAP"
"1","(-7450,3625)","2","mstr_standard","I30";
;
CDS_LIB"mstr_standard"
BODY_TYPE"PLUMBING"
HDL_TAP"TRUE";
"B \NAC \NWC"4;
"S \NAC"
BN"7"172;
%"TAP"
"1","(-7450,3725)","2","mstr_standard","I31";
;
CDS_LIB"mstr_standard"
BODY_TYPE"PLUMBING"
HDL_TAP"TRUE";
"B \NAC \NWC"1;
"S \NAC"
BN"0"157;
%"TAP"
"1","(-7450,3775)","2","mstr_standard","I32";
;
CDS_LIB"mstr_standard"
BODY_TYPE"PLUMBING"
HDL_TAP"TRUE";
"B \NAC \NWC"1;
"S \NAC"
BN"1"173;
%"TAP"
"1","(-7450,3825)","2","mstr_standard","I33";
;
CDS_LIB"mstr_standard"
BODY_TYPE"PLUMBING"
HDL_TAP"TRUE";
"B \NAC \NWC"1;
"S \NAC"
BN"2"158;
%"TAP"
"1","(-7450,3875)","2","mstr_standard","I34";
;
CDS_LIB"mstr_standard"
BODY_TYPE"PLUMBING"
HDL_TAP"TRUE";
"B \NAC \NWC"1;
"S \NAC"
BN"3"159;
%"TAP"
"1","(-7450,3925)","2","mstr_standard","I35";
;
CDS_LIB"mstr_standard"
BODY_TYPE"PLUMBING"
HDL_TAP"TRUE";
"B \NAC \NWC"1;
"S \NAC"
BN"4"174;
%"TAP"
"1","(-7450,3975)","2","mstr_standard","I36";
;
CDS_LIB"mstr_standard"
BODY_TYPE"PLUMBING"
HDL_TAP"TRUE";
"B \NAC \NWC"1;
"S \NAC"
BN"5"160;
%"TAP"
"1","(-7450,4025)","2","mstr_standard","I37";
;
CDS_LIB"mstr_standard"
BODY_TYPE"PLUMBING"
HDL_TAP"TRUE";
"B \NAC \NWC"1;
"S \NAC"
BN"6"161;
%"TAP"
"1","(-7450,4075)","2","mstr_standard","I38";
;
CDS_LIB"mstr_standard"
BODY_TYPE"PLUMBING"
HDL_TAP"TRUE";
"B \NAC \NWC"1;
"S \NAC"
BN"7"175;
%"TAP"
"1","(-5750,2325)","0","mstr_standard","I46";
;
CDS_LIB"mstr_standard"
BODY_TYPE"PLUMBING"
HDL_TAP"TRUE";
"B \NAC \NWC"6;
"S \NAC"
BN"1"89;
%"TAP"
"1","(-5750,2275)","0","mstr_standard","I47";
;
CDS_LIB"mstr_standard"
BODY_TYPE"PLUMBING"
HDL_TAP"TRUE";
"B \NAC \NWC"6;
"S \NAC"
BN"0"88;
%"TAP"
"1","(-5750,2475)","0","mstr_standard","I48";
;
CDS_LIB"mstr_standard"
BODY_TYPE"PLUMBING"
HDL_TAP"TRUE";
"B \NAC \NWC"6;
"S \NAC"
BN"4"92;
%"TAP"
"1","(-5750,2425)","0","mstr_standard","I49";
;
CDS_LIB"mstr_standard"
BODY_TYPE"PLUMBING"
HDL_TAP"TRUE";
"B \NAC \NWC"6;
"S \NAC"
BN"3"91;
%"TAP"
"1","(-5750,2375)","0","mstr_standard","I50";
;
CDS_LIB"mstr_standard"
BODY_TYPE"PLUMBING"
HDL_TAP"TRUE";
"B \NAC \NWC"6;
"S \NAC"
BN"2"90;
%"TAP"
"1","(-5750,2525)","0","mstr_standard","I51";
;
CDS_LIB"mstr_standard"
BODY_TYPE"PLUMBING"
HDL_TAP"TRUE";
"B \NAC \NWC"6;
"S \NAC"
BN"5"93;
%"TAP"
"1","(-5750,2575)","0","mstr_standard","I52";
;
CDS_LIB"mstr_standard"
BODY_TYPE"PLUMBING"
HDL_TAP"TRUE";
"B \NAC \NWC"6;
"S \NAC"
BN"6"94;
%"TAP"
"1","(-5750,2725)","0","mstr_standard","I53";
;
CDS_LIB"mstr_standard"
BODY_TYPE"PLUMBING"
HDL_TAP"TRUE";
"B \NAC \NWC"6;
"S \NAC"
BN"9"97;
%"TAP"
"1","(-5750,2675)","0","mstr_standard","I54";
;
CDS_LIB"mstr_standard"
BODY_TYPE"PLUMBING"
HDL_TAP"TRUE";
"B \NAC \NWC"6;
"S \NAC"
BN"8"96;
%"TAP"
"1","(-5750,2625)","0","mstr_standard","I55";
;
CDS_LIB"mstr_standard"
BODY_TYPE"PLUMBING"
HDL_TAP"TRUE";
"B \NAC \NWC"6;
"S \NAC"
BN"7"95;
%"TAP"
"1","(-5750,2775)","0","mstr_standard","I56";
;
CDS_LIB"mstr_standard"
BODY_TYPE"PLUMBING"
HDL_TAP"TRUE";
"B \NAC \NWC"6;
"S \NAC"
BN"10"98;
%"TAP"
"1","(-5750,2825)","0","mstr_standard","I57";
;
CDS_LIB"mstr_standard"
BODY_TYPE"PLUMBING"
HDL_TAP"TRUE";
"B \NAC \NWC"6;
"S \NAC"
BN"11"99;
%"TAP"
"1","(-5750,2975)","0","mstr_standard","I58";
;
CDS_LIB"mstr_standard"
BODY_TYPE"PLUMBING"
HDL_TAP"TRUE";
"B \NAC \NWC"6;
"S \NAC"
BN"14"102;
%"TAP"
"1","(-5750,2925)","0","mstr_standard","I59";
;
CDS_LIB"mstr_standard"
BODY_TYPE"PLUMBING"
HDL_TAP"TRUE";
"B \NAC \NWC"6;
"S \NAC"
BN"13"101;
%"TAP"
"1","(-5750,2875)","0","mstr_standard","I60";
;
CDS_LIB"mstr_standard"
BODY_TYPE"PLUMBING"
HDL_TAP"TRUE";
"B \NAC \NWC"6;
"S \NAC"
BN"12"100;
%"TAP"
"1","(-5750,3075)","0","mstr_standard","I61";
;
CDS_LIB"mstr_standard"
BODY_TYPE"PLUMBING"
HDL_TAP"TRUE";
"B \NAC \NWC"6;
"S \NAC"
BN"16"104;
%"TAP"
"1","(-5750,3025)","0","mstr_standard","I62";
;
CDS_LIB"mstr_standard"
BODY_TYPE"PLUMBING"
HDL_TAP"TRUE";
"B \NAC \NWC"6;
"S \NAC"
BN"15"103;
%"TAP"
"1","(-5750,3125)","0","mstr_standard","I63";
;
CDS_LIB"mstr_standard"
BODY_TYPE"PLUMBING"
HDL_TAP"TRUE";
"B \NAC \NWC"6;
"S \NAC"
BN"17"105;
%"TAP"
"1","(-5750,3225)","0","mstr_standard","I64";
;
CDS_LIB"mstr_standard"
BODY_TYPE"PLUMBING"
HDL_TAP"TRUE";
"B \NAC \NWC"6;
"S \NAC"
BN"19"107;
%"TAP"
"1","(-5750,3175)","0","mstr_standard","I65";
;
CDS_LIB"mstr_standard"
BODY_TYPE"PLUMBING"
HDL_TAP"TRUE";
"B \NAC \NWC"6;
"S \NAC"
BN"18"106;
%"TAP"
"1","(-5750,3275)","0","mstr_standard","I66";
;
CDS_LIB"mstr_standard"
BODY_TYPE"PLUMBING"
HDL_TAP"TRUE";
"B \NAC \NWC"6;
"S \NAC"
BN"20"108;
%"TAP"
"1","(-5750,3325)","0","mstr_standard","I67";
;
CDS_LIB"mstr_standard"
BODY_TYPE"PLUMBING"
HDL_TAP"TRUE";
"B \NAC \NWC"6;
"S \NAC"
BN"21"109;
%"TAP"
"1","(-5750,3375)","0","mstr_standard","I68";
;
CDS_LIB"mstr_standard"
BODY_TYPE"PLUMBING"
HDL_TAP"TRUE";
"B \NAC \NWC"6;
"S \NAC"
BN"22"110;
%"TAP"
"1","(-5750,3475)","0","mstr_standard","I69";
;
CDS_LIB"mstr_standard"
BODY_TYPE"PLUMBING"
HDL_TAP"TRUE";
"B \NAC \NWC"6;
"S \NAC"
BN"24"112;
%"TAP"
"1","(-5750,3425)","0","mstr_standard","I70";
;
CDS_LIB"mstr_standard"
BODY_TYPE"PLUMBING"
HDL_TAP"TRUE";
"B \NAC \NWC"6;
"S \NAC"
BN"23"111;
%"TAP"
"1","(-5750,3525)","0","mstr_standard","I71";
;
CDS_LIB"mstr_standard"
BODY_TYPE"PLUMBING"
HDL_TAP"TRUE";
"B \NAC \NWC"6;
"S \NAC"
BN"25"113;
%"TAP"
"1","(-5750,3575)","0","mstr_standard","I72";
;
CDS_LIB"mstr_standard"
BODY_TYPE"PLUMBING"
HDL_TAP"TRUE";
"B \NAC \NWC"6;
"S \NAC"
BN"26"114;
%"TAP"
"1","(-5750,3625)","0","mstr_standard","I73";
;
CDS_LIB"mstr_standard"
BODY_TYPE"PLUMBING"
HDL_TAP"TRUE";
"B \NAC \NWC"6;
"S \NAC"
BN"27"115;
%"TAP"
"1","(-5750,3725)","0","mstr_standard","I74";
;
CDS_LIB"mstr_standard"
BODY_TYPE"PLUMBING"
HDL_TAP"TRUE";
"B \NAC \NWC"6;
"S \NAC"
BN"29"117;
%"TAP"
"1","(-5750,3675)","0","mstr_standard","I75";
;
CDS_LIB"mstr_standard"
BODY_TYPE"PLUMBING"
HDL_TAP"TRUE";
"B \NAC \NWC"6;
"S \NAC"
BN"28"116;
%"TAP"
"1","(-5750,3775)","0","mstr_standard","I76";
;
CDS_LIB"mstr_standard"
BODY_TYPE"PLUMBING"
HDL_TAP"TRUE";
"B \NAC \NWC"6;
"S \NAC"
BN"30"118;
%"TAP"
"1","(-5750,3825)","0","mstr_standard","I77";
;
CDS_LIB"mstr_standard"
BODY_TYPE"PLUMBING"
HDL_TAP"TRUE";
"B \NAC \NWC"6;
"S \NAC"
BN"31"119;
%"TAP"
"1","(-5750,3975)","0","mstr_standard","I78";
;
CDS_LIB"mstr_standard"
BODY_TYPE"PLUMBING"
HDL_TAP"TRUE";
"B \NAC \NWC"5;
"S \NAC"
BN"1"121;
%"TAP"
"1","(-5750,3925)","0","mstr_standard","I79";
;
CDS_LIB"mstr_standard"
BODY_TYPE"PLUMBING"
HDL_TAP"TRUE";
"B \NAC \NWC"5;
"S \NAC"
BN"0"120;
%"VCC_CORE"
"1","(-8500,3550)","0","mstr_symbols","I8";
;
HDL_POWER"P3V3_STBY"
CDS_LIB"mstr_symbols"
VOLTAGE"3.3"
ROOM"PVCCINFAON_CPU1_CTRL";
"A"20;
%"TAP"
"1","(-5750,4075)","0","mstr_standard","I80";
;
CDS_LIB"mstr_standard"
BODY_TYPE"PLUMBING"
HDL_TAP"TRUE";
"B \NAC \NWC"5;
"S \NAC"
BN"3"123;
%"TAP"
"1","(-5750,4125)","0","mstr_standard","I81";
;
CDS_LIB"mstr_standard"
BODY_TYPE"PLUMBING"
HDL_TAP"TRUE";
"B \NAC \NWC"5;
"S \NAC"
BN"4"124;
%"TAP"
"1","(-5750,4025)","0","mstr_standard","I82";
;
CDS_LIB"mstr_standard"
BODY_TYPE"PLUMBING"
HDL_TAP"TRUE";
"B \NAC \NWC"5;
"S \NAC"
BN"2"122;
%"TAP"
"1","(-7450,4775)","2","mstr_standard","I85";
;
CDS_LIB"mstr_standard"
BODY_TYPE"PLUMBING"
HDL_TAP"TRUE";
"B \NAC \NWC"2;
"S \NAC"
BN"0"171;
%"TAP"
"1","(-7450,4825)","2","mstr_standard","I86";
;
CDS_LIB"mstr_standard"
BODY_TYPE"PLUMBING"
HDL_TAP"TRUE";
"B \NAC \NWC"2;
"S \NAC"
BN"1"170;
%"TAP"
"1","(-7450,4875)","2","mstr_standard","I87";
;
CDS_LIB"mstr_standard"
BODY_TYPE"PLUMBING"
HDL_TAP"TRUE";
"B \NAC \NWC"2;
"S \NAC"
BN"2"168;
%"TAP"
"1","(-7450,4925)","2","mstr_standard","I88";
;
CDS_LIB"mstr_standard"
BODY_TYPE"PLUMBING"
HDL_TAP"TRUE";
"B \NAC \NWC"2;
"S \NAC"
BN"3"167;
%"TAP"
"1","(-7450,4975)","2","mstr_standard","I89";
;
CDS_LIB"mstr_standard"
BODY_TYPE"PLUMBING"
HDL_TAP"TRUE";
"B \NAC \NWC"2;
"S \NAC"
BN"4"165;
%"TAP"
"1","(-7450,5025)","2","mstr_standard","I90";
;
CDS_LIB"mstr_standard"
BODY_TYPE"PLUMBING"
HDL_TAP"TRUE";
"B \NAC \NWC"2;
"S \NAC"
BN"5"163;
%"TAP"
"1","(-7450,5075)","2","mstr_standard","I91";
;
CDS_LIB"mstr_standard"
BODY_TYPE"PLUMBING"
HDL_TAP"TRUE";
"B \NAC \NWC"2;
"S \NAC"
BN"6"162;
%"TAP"
"1","(-7450,5225)","2","mstr_standard","I92";
;
CDS_LIB"mstr_standard"
BODY_TYPE"PLUMBING"
HDL_TAP"TRUE";
"B \NAC \NWC"3;
"S \NAC"
BN"1"31;
%"TAP"
"1","(-7450,5175)","2","mstr_standard","I93";
;
CDS_LIB"mstr_standard"
BODY_TYPE"PLUMBING"
HDL_TAP"TRUE";
"B \NAC \NWC"3;
"S \NAC"
BN"0"80;
%"TAP"
"1","(-7450,5275)","2","mstr_standard","I94";
;
CDS_LIB"mstr_standard"
BODY_TYPE"PLUMBING"
HDL_TAP"TRUE";
"B \NAC \NWC"3;
"S \NAC"
BN"2"169;
%"TAP"
"1","(-7450,5325)","2","mstr_standard","I95";
;
CDS_LIB"mstr_standard"
BODY_TYPE"PLUMBING"
HDL_TAP"TRUE";
"B \NAC \NWC"3;
"S \NAC"
BN"3"30;
%"TAP"
"1","(-7450,5375)","2","mstr_standard","I96";
;
CDS_LIB"mstr_standard"
BODY_TYPE"PLUMBING"
HDL_TAP"TRUE";
"B \NAC \NWC"3;
"S \NAC"
BN"4"166;
%"TAP"
"1","(-7450,5425)","2","mstr_standard","I97";
;
CDS_LIB"mstr_standard"
BODY_TYPE"PLUMBING"
HDL_TAP"TRUE";
"B \NAC \NWC"3;
"S \NAC"
BN"5"164;
%"TAP"
"1","(-7450,5475)","2","mstr_standard","I98";
;
CDS_LIB"mstr_standard"
BODY_TYPE"PLUMBING"
HDL_TAP"TRUE";
"B \NAC \NWC"3;
"S \NAC"
BN"6"29;
%"TAP"
"1","(-5750,4225)","0","mstr_standard","I99";
;
CDS_LIB"mstr_standard"
BODY_TYPE"PLUMBING"
HDL_TAP"TRUE";
"B \NAC \NWC"5;
"S \NAC"
BN"6"126;
END.
